FILE_TYPE = CONNECTIVITY;
{Allegro Design Entry HDL 16.6-p007 (v16-6-112F) 10/10/2012}
"PAGE_NUMBER" = 92;
0"NC";
1"PVCCIO_CPU1\g";
2"PVCCIO_CPU0\g";
3"GND\g";
4"GND\g";
5"GND\g";
6"P3V3\g";
7"GND\g";
8"GND\g";
9"PVCCIO_CPU0\g";
10"GND\g";
11"P3V3\g";
12"PVCCIO_CPU0\g";
13"GND\g";
14"GND\g";
15"PVCCIO_CPU0\g";
16"GND\g";
17"PVCCIO_CPU0\g";
18"PVCCIO_CPU0\g";
19"FM_CPU_CATERR_LVT3_R2_N";
20"FM_CPU1_FIVR_FAULT_R_LVT3";
21"FM_CPU_CATERR_LVT3_N";
22"H_CPU0_ERR2_G_N";
23"H_CPU1_ERR2_G_N";
24"H_CPU_ERR2_G_R_N";
25"H_CPU0_CATERR_G_N";
26"H_CPU0_MSMI_G_N";
27"H_CPU1_MSMI_G_N";
28"H_CPU1_CATERR_G_N";
29"H_CPU_MSMI_G_N";
30"H_CPU0_FIVR_FAULT_G";
31"H_CPU_ERR2_GTL_N";
32"H_CPU0_THERMTRIP_G_N";
33"FM_CPU_MSMI_LVT3_R_N";
34"FM_CPU_ERR2_LVT3_R_N";
35"FM_CPU0_FIVR_FAULT_R_LVT3";
36"PD_GTL2104_DIR_0";
37"FM_CPU0_THERMTRIP_LVT3_R_N";
38"P0V7_GTL2104_VREF_0"VOLTAGE"+0.7 V";
39"PWRGD_CPUPWRGD_R1";
40"H_CPU_CATERR_G_N";
41"H_CPU1_THERMTRIP_G_N";
42"H_CPU1_FIVR_FAULT_G";
43"PWRGD_CPUPWRGD_GTL";
44"FM_CPU1_THERMTRIP_LVT3_R_N";
45"PD_GTL2104_DIR_1";
46"P0V7_GTL2104_VREF_1"VOLTAGE"+0.7 V";
47"FM_CPU1_FIVR_FAULT_LVT3";
48"FM_CPU1_THERMTRIP_LVT3_N";
49"FM_CPU0_THERMTRIP_LVT3_N";
50"FM_CPU0_FIVR_FAULT_LVT3";
51"PWRGD_CPUPWRGD";
52"FM_CPU_MSMI_LVT3_N";
53"FM_CPU_ERR2_LVT3_N";
%"GTL2014"
"1","(-1825,4250)","2","mstr_digital","I1";
;
CDS_SEC"1"
ROOM"PROC_SIDEBAND"
CDS_LOCATION"U3P2"
SEC"1"
CDS_LIB"mstr_digital"
BOM_COST"PROC_SIDEBAND"
SEC_TYPE"SM"
PACK_TYPE"SM"
MATERIAL"IC"
PART_NUMBER"D66151-001"
LOCATION"U3P2";
"A0"
$PN"13"39;
"A1"
$PN"12"20;
"A3"
$PN"9"44;
"A2"
$PN"10"19;
"B2"
$PN"5"40;
"B3"
$PN"6"41;
"B0"
$PN"2"43;
"B1"
$PN"3"42;
"GND<1>"
$PN"8"3;
"GND<2>"
$PN"11"3;
"GND<0>"
$PN"7"3;
"VCC"
$PN"14"6;
"VREF"
$PN"4"46;
"DIR"
$PN"1"45;
%"PVCCIO_CPU1"
"1","(-2900,4750)","0","mstr_symbols","I10";
;
HDL_POWER"PVCCIO_CPU1"
BODY_TYPE"PLUMBING"
CDS_LIB"mstr_symbols"
VOLTAGE"1.1V";
"G\NAC"1;
%"RES"
"2","(-4350,4600)","0","mstr_discrete","I100";
;
CDS_SEC"1"
ROOM"PROC_SIDEBAND"
CDS_LOCATION"R7P18"
SEC"1"
SEC_TYPE"0402"
BOM_COST"PROC"
CDS_LIB"mstr_discrete"
WATTAGE"1/16W"
MATERIAL"CHIP"
PACK_TYPE"0402"
TOLERANCE"1%"
VALUE"150.0"
PART_NUMBER"G21796-009"
LOCATION"R7P18";
"A"
$PN"1"18;
"B"
$PN"2"28;
%"RES"
"2","(-4450,4600)","2","mstr_discrete","I101";
;
CDS_SEC"1"
ROOM"PROC_SIDEBAND"
CDS_LOCATION"R4R2"
SEC"1"
BOM_COST"PROC"
CDS_LIB"mstr_discrete"
SEC_TYPE"0402"
WATTAGE"1/16W"
MATERIAL"CHIP"
PACK_TYPE"0402"
TOLERANCE"1%"
VALUE"150.0"
PART_NUMBER"G21796-009"
LOCATION"R4R2";
"A"
$PN"1"18;
"B"
$PN"2"25;
%"PVCCIO_CPU0"
"1","(125,5425)","0","mstr_symbols","I104";
;
HDL_POWER"PVCCIO_CPU0"
BODY_TYPE"PLUMBING"
CDS_LIB"mstr_symbols"
VOLTAGE"1.1V";
"G\NAC"2;
%"RES"
"1","(-125,3750)","0","mstr_discrete","I12";
;
CDS_SEC"1"
ROOM"PROC_SIDEBAND"
CDS_LOCATION"R3P46"
SEC"1"
CDS_LIB"mstr_discrete"
BOM_COST"PROC_SIDEBAND"
SEC_TYPE"0402"
WATTAGE"1/16W"
MATERIAL"CHIP"
PACK_TYPE"0402"
TOLERANCE"1%"
VALUE"33.2"
PART_NUMBER"G21796-074"
LOCATION"R3P46";
"B"
$PN"2"47;
"A"
$PN"1"20;
%"RES"
"1","(-125,4000)","0","mstr_discrete","I13";
;
CDS_SEC"1"
ROOM"PROC_SIDEBAND"
CDS_LOCATION"R3P43"
SEC"1"
CDS_LIB"mstr_discrete"
BOM_COST"PROC_SIDEBAND"
SEC_TYPE"0402"
LOCATION"R3P43"
WATTAGE"1/16W"
MATERIAL"CHIP"
PACK_TYPE"0402"
TOLERANCE"1%"
VALUE"33.2"
PART_NUMBER"G21796-074";
"B"
$PN"2"21;
"A"
$PN"1"19;
%"RES"
"1","(-125,4250)","0","mstr_discrete","I14";
;
CDS_SEC"1"
ROOM"PROC_SIDEBAND"
CDS_LOCATION"R3P42"
SEC"1"
CDS_LIB"mstr_discrete"
BOM_COST"PROC_SIDEBAND"
SEC_TYPE"0402"
WATTAGE"1/16W"
MATERIAL"CHIP"
PACK_TYPE"0402"
TOLERANCE"1%"
VALUE"33.2"
PART_NUMBER"G21796-074"
LOCATION"R3P42";
"B"
$PN"2"48;
"A"
$PN"1"44;
%"RES"
"2","(-2850,2325)","0","mstr_discrete","I19";
;
CDS_SEC"1"
ROOM"PROC_SIDEBAND"
CDS_LOCATION"R7E2"
SEC"1"
BOM_COST"PROC_SIDEBAND"
CDS_LIB"mstr_discrete"
SEC_TYPE"0402"
WATTAGE"1/16W"
MATERIAL"CHIP"
PACK_TYPE"0402"
TOLERANCE"1.0%"
VALUE"75"
PART_NUMBER"G21796-267"
LOCATION"R7E2";
"A"
$PN"1"15;
"B"
$PN"2"32;
%"GND"
"1","(-2550,3725)","0","mstr_symbols","I2";
;
HDL_POWER"GND"
BODY_TYPE"PLUMBING"
CDS_LIB"mstr_symbols"
SIZE"1B"
VOLTAGE"0";
"A\NAC"3;
%"RES"
"1","(-125,2050)","0","mstr_discrete","I24";
;
CDS_SEC"1"
ROOM"PROC_SIDEBAND"
CDS_LOCATION"R7D34"
SEC"1"
CDS_LIB"mstr_discrete"
BOM_COST"PROC_SIDEBAND"
SEC_TYPE"0402"
WATTAGE"1/16W"
MATERIAL"CHIP"
PACK_TYPE"0402"
TOLERANCE"1%"
VALUE"33.2"
PART_NUMBER"G21796-074"
LOCATION"R7D34";
"B"
$PN"2"49;
"A"
$PN"1"37;
%"RES"
"1","(-100,1800)","0","mstr_discrete","I29";
;
CDS_SEC"1"
ROOM"PROC_SIDEBAND"
CDS_LOCATION"R7D31"
SEC"1"
CDS_LIB"mstr_discrete"
BOM_COST"PROC_SIDEBAND"
SEC_TYPE"0402"
WATTAGE"1/16W"
MATERIAL"CHIP"
PACK_TYPE"0402"
TOLERANCE"1%"
VALUE"33.2"
PART_NUMBER"G21796-074"
LOCATION"R7D31";
"B"
$PN"2"53;
"A"
$PN"1"34;
%"RES"
"1","(-100,1550)","0","mstr_discrete","I30";
;
CDS_SEC"1"
ROOM"PROC_SIDEBAND"
CDS_LOCATION"R7D29"
SEC"1"
SEC_TYPE"0402"
CDS_LIB"mstr_discrete"
BOM_COST"PROC_SIDEBAND"
WATTAGE"1/16W"
MATERIAL"CHIP"
PACK_TYPE"0402"
TOLERANCE"1%"
VALUE"33.2"
PART_NUMBER"G21796-074"
LOCATION"R7D29";
"B"
$PN"2"50;
"A"
$PN"1"35;
%"GTL2014"
"1","(-1750,2050)","2","mstr_digital","I32";
;
CDS_SEC"1"
ROOM"PROC_SIDEBAND"
CDS_LOCATION"U7D2"
SEC"1"
SEC_TYPE"SM"
BOM_COST"PROC_SIDEBAND"
CDS_LIB"mstr_digital"
PACK_TYPE"SM"
MATERIAL"IC"
PART_NUMBER"D66151-001"
LOCATION"U7D2";
"A0"
$PN"13"33;
"A1"
$PN"12"35;
"A3"
$PN"9"37;
"A2"
$PN"10"34;
"B2"
$PN"5"31;
"B3"
$PN"6"32;
"B0"
$PN"2"29;
"B1"
$PN"3"30;
"GND<1>"
$PN"8"4;
"GND<2>"
$PN"11"4;
"GND<0>"
$PN"7"4;
"VCC"
$PN"14"11;
"VREF"
$PN"4"38;
"DIR"
$PN"1"36;
%"GND"
"1","(-2475,1525)","0","mstr_symbols","I33";
;
HDL_POWER"GND"
BODY_TYPE"PLUMBING"
SIZE"1B"
CDS_LIB"mstr_symbols"
VOLTAGE"0";
"A\NAC"4;
%"CAP_A"
"1","(-300,4825)","0","dev_discrete","I37";
;
SEC"1"
SEC_TYPE"0402V"
CDS_SEC"1"
CDS_LIB"dev_discrete"
BOM_COST"PROC_SIDEBAND"
CDS_LOCATION"C3P49"
ROOM"PROC_SIDEBAND"
MATERIAL"X7R"
VOLTAGE"16V"
PACK_TYPE"0402V"
TOLERANCE"10%"
VALUE"0.1UF"
PART_NUMBER"A36096-030"
LOCATION"C3P49";
"B"
$PN"2"5;
"A"
$PN"1"46;
%"RES"
"2","(125,4800)","0","mstr_discrete","I38";
;
CDS_SEC"1"
ROOM"PROC_SIDEBAND"
CDS_LOCATION"R3P49"
SEC"1"
BOM_COST"PROC_SIDEBAND"
CDS_LIB"mstr_discrete"
SEC_TYPE"0402"
WATTAGE"1/16W"
MATERIAL"CHIP"
PACK_TYPE"0402"
TOLERANCE"1%"
VALUE"100.0"
PART_NUMBER"G21796-017"
LOCATION"R3P49";
"A"
$PN"1"46;
"B"
$PN"2"5;
%"RES"
"2","(125,5200)","0","mstr_discrete","I39";
;
CDS_SEC"1"
ROOM"PROC_SIDEBAND"
CDS_LOCATION"R3P45"
SEC"1"
BOM_COST"PROC_SIDEBAND"
CDS_LIB"mstr_discrete"
SEC_TYPE"0402"
WATTAGE"1/16W"
MATERIAL"CHIP"
PACK_TYPE"0402"
TOLERANCE"1%"
VALUE"49.9"
PART_NUMBER"G21796-047"
LOCATION"R3P45";
"A"
$PN"1"2;
"B"
$PN"2"46;
%"GND"
"1","(125,4450)","0","mstr_symbols","I41";
;
HDL_POWER"GND"
BODY_TYPE"PLUMBING"
SIZE"1B"
CDS_LIB"mstr_symbols"
VOLTAGE"0";
"A\NAC"5;
%"P3V3"
"1","(-1175,4950)","0","mstr_symbols","I42";
;
HDL_POWER"P3V3"
BODY_TYPE"PLUMBING"
CDS_LIB"mstr_symbols"
SIZE"1B"
VOLTAGE"3.3V";
"G\NAC"6;
%"RES"
"1","(-675,4400)","0","mstr_discrete","I46";
;
CDS_SEC"1"
ROOM"PROC_SIDEBAND"
CDS_LOCATION"R3R1"
SEC"1"
BOM_COST"PROC_SIDEBAND"
CDS_LIB"mstr_discrete"
SEC_TYPE"0402"
WATTAGE"1/16W"
MATERIAL"CHIP"
PACK_TYPE"0402"
TOLERANCE"1%"
VALUE"1.00K"
PART_NUMBER"G21796-026"
LOCATION"R3R1";
"B"
$PN"2"7;
"A"
$PN"1"45;
%"GND"
"1","(-300,4325)","0","mstr_symbols","I47";
;
HDL_POWER"GND"
BODY_TYPE"PLUMBING"
SIZE"1B"
CDS_LIB"mstr_symbols"
VOLTAGE"0";
"A\NAC"7;
%"RES"
"2","(350,2525)","0","mstr_discrete","I48";
;
CDS_SEC"1"
ROOM"PROC_SIDEBAND"
CDS_LOCATION"R7D32"
SEC"1"
SEC_TYPE"0402"
BOM_COST"PROC_SIDEBAND"
CDS_LIB"mstr_discrete"
WATTAGE"1/16W"
MATERIAL"CHIP"
PACK_TYPE"0402"
TOLERANCE"1%"
VALUE"100.0"
PART_NUMBER"G21796-017"
LOCATION"R7D32";
"A"
$PN"1"38;
"B"
$PN"2"8;
%"GND"
"1","(350,2175)","0","mstr_symbols","I49";
;
HDL_POWER"GND"
BODY_TYPE"PLUMBING"
CDS_LIB"mstr_symbols"
SIZE"1B"
VOLTAGE"0";
"A\NAC"8;
%"PVCCIO_CPU0"
"1","(350,3275)","0","mstr_symbols","I50";
;
HDL_POWER"PVCCIO_CPU0"
BODY_TYPE"PLUMBING"
CDS_LIB"mstr_symbols"
VOLTAGE"1.1V";
"G\NAC"9;
%"RES"
"2","(350,3050)","0","mstr_discrete","I51";
;
CDS_SEC"1"
ROOM"PROC_SIDEBAND"
CDS_LOCATION"R7D33"
SEC"1"
SEC_TYPE"0402"
BOM_COST"PROC_SIDEBAND"
CDS_LIB"mstr_discrete"
WATTAGE"1/16W"
MATERIAL"CHIP"
PACK_TYPE"0402"
TOLERANCE"1%"
VALUE"49.9"
PART_NUMBER"G21796-047"
LOCATION"R7D33";
"A"
$PN"1"9;
"B"
$PN"2"38;
%"CAP_A"
"1","(-75,2550)","0","dev_discrete","I52";
;
SEC"1"
SEC_TYPE"0402V"
CDS_SEC"1"
CDS_LIB"dev_discrete"
BOM_COST"PROC_SIDEBAND"
CDS_LOCATION"C7D5"
ROOM"PROC_SIDEBAND"
MATERIAL"X7R"
VOLTAGE"16V"
PACK_TYPE"0402V"
TOLERANCE"10%"
VALUE"0.1UF"
PART_NUMBER"A36096-030"
LOCATION"C7D5";
"B"
$PN"2"8;
"A"
$PN"1"38;
%"GND"
"1","(-225,2125)","0","mstr_symbols","I53";
;
HDL_POWER"GND"
BODY_TYPE"PLUMBING"
SIZE"1B"
CDS_LIB"mstr_symbols"
VOLTAGE"0";
"A\NAC"10;
%"RES"
"1","(-600,2200)","0","mstr_discrete","I54";
;
CDS_SEC"1"
ROOM"PROC_SIDEBAND"
CDS_LOCATION"R7D26"
SEC"1"
SEC_TYPE"0402"
CDS_LIB"mstr_discrete"
BOM_COST"PROC_SIDEBAND"
WATTAGE"1/16W"
MATERIAL"CHIP"
PACK_TYPE"0402"
TOLERANCE"1%"
VALUE"1.00K"
PART_NUMBER"G21796-026"
LOCATION"R7D26";
"B"
$PN"2"10;
"A"
$PN"1"36;
%"P3V3"
"1","(-1050,2750)","0","mstr_symbols","I58";
;
HDL_POWER"P3V3"
BODY_TYPE"PLUMBING"
SIZE"1B"
CDS_LIB"mstr_symbols"
VOLTAGE"3.3V";
"G\NAC"11;
%"RES"
"1","(-125,3550)","0","mstr_discrete","I61";
;
CDS_SEC"1"
ROOM"PROC_SIDEBAND"
CDS_LOCATION"R3R3"
SEC"1"
CDS_LIB"mstr_discrete"
BOM_COST"PROC_SIDEBAND"
SEC_TYPE"0402"
WATTAGE"1/16W"
MATERIAL"CHIP"
PACK_TYPE"0402"
TOLERANCE"1%"
VALUE"33.2"
PART_NUMBER"G21796-074"
LOCATION"R3R3";
"B"
$PN"2"51;
"A"
$PN"1"39;
%"RES"
"2","(-4600,1825)","2","mstr_discrete","I64";
;
CDS_SEC"1"
ROOM"PROC_SIDEBAND"
CDS_LOCATION"R6D9"
SEC"1"
CDS_LIB"mstr_discrete"
BOM_COST"PROC_SIDEBAND"
SEC_TYPE"0402"
WATTAGE"1/16W"
MATERIAL"CHIP"
PACK_TYPE"0402"
TOLERANCE"1%"
VALUE"150.0"
PART_NUMBER"G21796-009"
LOCATION"R6D9";
"A"
$PN"1"12;
"B"
$PN"2"26;
%"RES"
"2","(-4275,1800)","0","mstr_discrete","I65";
;
CDS_SEC"1"
ROOM"PROC_SIDEBAND"
CDS_LOCATION"R7P27"
SEC"1"
SEC_TYPE"0402"
BOM_COST"PROC_SIDEBAND"
CDS_LIB"mstr_discrete"
WATTAGE"1/16W"
MATERIAL"CHIP"
PACK_TYPE"0402"
TOLERANCE"1%"
VALUE"150.0"
PART_NUMBER"G21796-009"
LOCATION"R7P27";
"A"
$PN"1"12;
"B"
$PN"2"27;
%"PVCCIO_CPU0"
"1","(-4600,2050)","0","mstr_symbols","I66";
;
HDL_POWER"PVCCIO_CPU0"
BODY_TYPE"PLUMBING"
CDS_LIB"mstr_symbols"
VOLTAGE"1.1V";
"G\NAC"12;
%"RES"
"1","(-3725,1275)","0","mstr_discrete","I67";
;
CDS_SEC"1"
ROOM"PROC_SIDEBAND"
CDS_LOCATION"R7D28"
SEC"1"
SEC_TYPE"0402"
CDS_LIB"mstr_discrete"
BOM_COST"PROC_SIDEBAND"
WATTAGE"1/16W"
MATERIAL"CHIP"
PACK_TYPE"0402"
TOLERANCE"5%"
VALUE"0.0"
PART_NUMBER"G21497-005"
LOCATION"R7D28";
"B"
$PN"2"29;
"A"
$PN"1"27;
%"RES"
"1","(-3775,1550)","0","mstr_discrete","I68";
;
CDS_SEC"1"
ROOM"PROC_SIDEBAND"
CDS_LOCATION"R7D27"
SEC"1"
BOM_COST"PROC_SIDEBAND"
SEC_TYPE"0402"
CDS_LIB"mstr_discrete"
WATTAGE"1/16W"
MATERIAL"CHIP"
PACK_TYPE"0402"
TOLERANCE"5%"
VALUE"0.0"
PART_NUMBER"G21497-005"
LOCATION"R7D27";
"B"
$PN"2"29;
"A"
$PN"1"26;
%"RES"
"1","(-100,1250)","0","mstr_discrete","I70";
;
CDS_SEC"1"
ROOM"PROC_SIDEBAND"
CDS_LOCATION"R7D25"
SEC"1"
CDS_LIB"mstr_discrete"
BOM_COST"PROC_SIDEBAND"
SEC_TYPE"0402"
WATTAGE"1/16W"
MATERIAL"CHIP"
PACK_TYPE"0402"
TOLERANCE"1%"
VALUE"33.2"
PART_NUMBER"G21796-074"
LOCATION"R7D25";
"B"
$PN"2"52;
"A"
$PN"1"33;
%"RES"
"2","(-2925,3900)","0","mstr_discrete","I75";
;
CDS_SEC"1"
ROOM"PROC_SIDEBAND"
CDS_LOCATION"R3R2"
SEC"1"
SEC_TYPE"0402"
CDS_LIB"mstr_discrete"
WATTAGE"1/16W"
MATERIAL"CHIP"
PACK_TYPE"0402"
TOLERANCE"1%"
VALUE"1.00K"
PART_NUMBER"G21796-026"
LOCATION"R3R2";
"A"
$PN"1"42;
"B"
$PN"2"13;
%"GND"
"1","(-2925,3650)","0","mstr_symbols","I76";
;
HDL_POWER"GND"
BODY_TYPE"PLUMBING"
CDS_LIB"mstr_symbols"
SIZE"1B"
VOLTAGE"0";
"A\NAC"13;
%"CAP"
"1","(-900,2525)","0","mstr_discrete","I79";
;
CDS_SEC"1"
ROOM"PROC_SIDEBAND"
CDS_LOCATION"C7D4"
SEC"1"
BOM_COST"PROC"
SEC_TYPE"0402"
CDS_LIB"mstr_discrete"
MATERIAL"X6S"
VOLTAGE"16V"
PACK_TYPE"0402"
TOLERANCE"10%"
VALUE"1.0UF"
PART_NUMBER"D97712-011"
LOCATION"C7D4";
"A"
$PN"1"11;
"B"
$PN"2"14;
%"GND"
"1","(-900,2350)","0","mstr_symbols","I80";
;
HDL_POWER"GND"
BODY_TYPE"PLUMBING"
SIZE"1B"
CDS_LIB"mstr_symbols"
VOLTAGE"0";
"A\NAC"14;
%"PVCCIO_CPU0"
"1","(-2850,2700)","0","mstr_symbols","I82";
;
HDL_POWER"PVCCIO_CPU0"
BODY_TYPE"PLUMBING"
CDS_LIB"mstr_symbols"
VOLTAGE"1.1V";
"G\NAC"15;
%"CAP"
"1","(-1025,4725)","0","mstr_discrete","I84";
;
CDS_SEC"1"
ROOM"PROC_SIDEBAND"
CDS_LOCATION"C3P50"
SEC"1"
BOM_COST"PROC"
CDS_LIB"mstr_discrete"
SEC_TYPE"0402"
MATERIAL"X6S"
VOLTAGE"16V"
PACK_TYPE"0402"
TOLERANCE"10%"
VALUE"1.0UF"
PART_NUMBER"D97712-011"
LOCATION"C3P50";
"A"
$PN"1"6;
"B"
$PN"2"16;
%"GND"
"1","(-1025,4550)","0","mstr_symbols","I85";
;
HDL_POWER"GND"
BODY_TYPE"PLUMBING"
CDS_LIB"mstr_symbols"
SIZE"1B"
VOLTAGE"0";
"A\NAC"16;
%"RES"
"2","(-2900,4525)","0","mstr_discrete","I9";
;
CDS_SEC"1"
ROOM"PROC_SIDEBAND"
CDS_LOCATION"R3P41"
SEC"1"
SEC_TYPE"0402"
BOM_COST"PROC_SIDEBAND"
CDS_LIB"mstr_discrete"
WATTAGE"1/16W"
MATERIAL"CHIP"
PACK_TYPE"0402"
TOLERANCE"1.0%"
VALUE"75"
PART_NUMBER"G21796-267"
LOCATION"R3P41";
"A"
$PN"1"1;
"B"
$PN"2"41;
%"RES"
"1","(-4575,2550)","0","mstr_discrete","I92";
;
ROOM"PROC_SIDEBAND"
CDS_LOCATION"R2T44"
$SEC"1"
CDS_SEC"1"
CDS_LIB"mstr_discrete"
BOM_COST"PROC"
WATTAGE"1/16W"
MATERIAL"CHIP"
PACK_TYPE"0402"
TOLERANCE"5%"
VALUE"0.0"
PART_NUMBER"G21497-005"
LOCATION"R2T44";
"B"
$PN"2"24;
"A"
$PN"1"23;
%"RES"
"1","(-4600,2800)","0","mstr_discrete","I93";
;
ROOM"PROC_SIDEBAND"
CDS_LOCATION"R2T40"
$SEC"1"
CDS_SEC"1"
CDS_LIB"mstr_discrete"
BOM_COST"PROC"
WATTAGE"1/16W"
MATERIAL"CHIP"
PACK_TYPE"0402"
TOLERANCE"5%"
VALUE"0.0"
PART_NUMBER"G21497-005"
LOCATION"R2T40";
"B"
$PN"2"24;
"A"
$PN"1"22;
%"RES"
"2","(-4000,2950)","0","mstr_discrete","I94";
;
ROOM"PROC_SIDEBAND"
CDS_LOCATION"R2T37"
$SEC"1"
CDS_SEC"1"
BOM_COST"PROC"
CDS_LIB"mstr_discrete"
WATTAGE"1/16W"
MATERIAL"CHIP"
PACK_TYPE"0402"
TOLERANCE"1%"
VALUE"200.0"
PART_NUMBER"G21796-004"
LOCATION"R2T37";
"A"
$PN"1"17;
"B"
$PN"2"24;
%"PVCCIO_CPU0"
"1","(-4000,3175)","0","mstr_symbols","I95";
;
HDL_POWER"PVCCIO_CPU0"
BODY_TYPE"PLUMBING"
CDS_LIB"mstr_symbols"
VOLTAGE"1.1V";
"G\NAC"17;
%"RES"
"1","(-3675,2675)","0","mstr_discrete","I96";
;
ROOM"PROC_SIDEBAND"
CDS_LOCATION"R2T43"
$SEC"1"
CDS_SEC"1"
CDS_LIB"mstr_discrete"
BOM_COST"PROC"
WATTAGE"1/16W"
MATERIAL"CHIP"
PACK_TYPE"0402"
TOLERANCE"1.0%"
VALUE"75"
PART_NUMBER"G21796-267"
LOCATION"R2T43";
"B"
$PN"2"31;
"A"
$PN"1"24;
%"RES"
"1","(-3775,4350)","0","mstr_discrete","I97";
;
CDS_SEC"1"
CDS_LOCATION"R3P59"
ROOM"PROC_SIDEBAND"
SEC"1"
BOM_COST"PROC"
SEC_TYPE"0402"
CDS_LIB"mstr_discrete"
WATTAGE"1/16W"
MATERIAL"CHIP"
PACK_TYPE"0402"
TOLERANCE"5%"
VALUE"0.0"
PART_NUMBER"G21497-005"
LOCATION"R3P59";
"B"
$PN"2"40;
"A"
$PN"1"25;
%"RES"
"1","(-3750,4100)","0","mstr_discrete","I98";
;
CDS_SEC"1"
CDS_LOCATION"R3P58"
ROOM"PROC_SIDEBAND"
SEC"1"
CDS_LIB"mstr_discrete"
SEC_TYPE"0402"
BOM_COST"PROC"
WATTAGE"1/16W"
MATERIAL"CHIP"
PACK_TYPE"0402"
TOLERANCE"5%"
VALUE"0.0"
PART_NUMBER"G21497-005"
LOCATION"R3P58";
"B"
$PN"2"40;
"A"
$PN"1"28;
%"PVCCIO_CPU0"
"1","(-4450,4850)","0","mstr_symbols","I99";
;
HDL_POWER"PVCCIO_CPU0"
BODY_TYPE"PLUMBING"
CDS_LIB"mstr_symbols"
VOLTAGE"1.1V";
"G\NAC"18;
END.
